#ISCELL
  logical_power cad_note *
  *
#ISCELL
  mstr_misc dns *
  *
#ISCELL
  pure_quanta quanta_title_block_c *
  *
#ISCELL
  standard offpage *
  page323_i1
#ISCELL
  logical_power universal_power *
  page323_i10
#ISCELL
  logical_power universal_gnd *
  page323_i2
#ISCELL
  logical_power universal_gnd *
  page323_i28
#ISCELL
  logical_power universal_gnd *
  page323_i29
#CELL
  pure_quanta q_cap *
  page323_i3
#CELL
  pure_quanta q_cap *
  page323_i30
#CELL
  pure_quanta mp5016gqhlz *
  page323_i31
#CELL
  pure_quanta q_cap *
  page323_i32
#ISCELL
  logical_power universal_gnd *
  page323_i33
#CELL
  pure_quanta q_cap *
  page323_i34
#ISCELL
  logical_power universal_power *
  page323_i35
#ISCELL
  logical_power gnd *
  page323_i36
#CELL
  pure_quanta q_cap *
  page323_i37
#ISCELL
  standard offpage *
  page323_i38
#ISCELL
  logical_power gnd *
  page323_i39
#CELL
  pure_quanta q_res *
  page323_i4
#CELL
  pure_quanta q_res *
  page323_i40
#ISCELL
  logical_power gnd *
  page323_i41
#CELL
  pure_quanta q_cap *
  page323_i42
#CELL
  pure_quanta q_res *
  page323_i43
#ISCELL
  logical_power gnd *
  page323_i44
#CELL
  pure_quanta q_res *
  page323_i45
#ISCELL
  logical_power gnd *
  page323_i46
#CELL
  pure_quanta q_cap *
  page323_i47
#ISCELL
  logical_power gnd *
  page323_i48
#CELL
  pure_quanta rs31312r *
  page323_i49
#CELL
  pure_quanta q_res *
  page323_i5
#ISCELL
  logical_power gnd *
  page323_i50
#CELL
  pure_quanta q_cap *
  page323_i51
#ISCELL
  logical_power universal_power *
  page323_i52
#CELL
  pure_quanta q_res *
  page323_i53
#CELL
  pure_quanta q_res *
  page323_i54
#CELL
  pure_quanta q_res *
  page323_i55
#CELL
  pure_quanta q_cap *
  page323_i56
#ISCELL
  logical_power gnd *
  page323_i57
#CELL
  pure_quanta q_res *
  page323_i58
#ISCELL
  standard offpage *
  page323_i59
#CELL
  pure_quanta q_res *
  page323_i6
#ISCELL
  standard offpage *
  page323_i60
#ISCELL
  logical_power vccaux15 *
  page323_i61
#CELL
  pure_quanta q_res *
  page323_i62
#CELL
  pure_quanta q_res *
  page323_i63
#CELL
  pure_quanta q_res *
  page323_i64
#ISCELL
  logical_power vccaux15 *
  page323_i65
#CELL
  pure_quanta q_res *
  page323_i66
#CELL
  pure_quanta q_res *
  page323_i67
#ISCELL
  logical_power gnd *
  page323_i68
#CELL
  pure_quanta q_cap *
  page323_i69
#ISCELL
  logical_power universal_gnd *
  page323_i7
#CELL
  pure_quanta q_res *
  page323_i70
#ISCELL
  logical_power universal_power *
  page323_i71
#ISCELL
  logical_power gnd *
  page323_i72
#CELL
  pure_quanta q_cap *
  page323_i73
#ISCELL
  standard offpage *
  page323_i74
#ISCELL
  standard offpage *
  page323_i75
#ISCELL
  standard offpage *
  page323_i76
#ISCELL
  logical_power universal_power *
  page323_i77
#ISCELL
  logical_power universal_gnd *
  page323_i8
#CELL
  pure_quanta q_cap *
  page323_i9
